FILE_TYPE = CONNECTIVITY;
{Allegro Design Entry HDL 17.4-2019 S026 (4007227) 1/17/2022}
"PAGE_NUMBER" = 94;
0"NC";
1"GND\g";
2"GND\g";
3"P3V3\g";
4"M_J_CPU0_SB_CB<7:0>";
5"M_J_CPU0_SA_CB<7:0>";
6"M_J_CPU0_SA_CA<6:0>";
7"M_J_CPU0_SB_CA<6:0>";
8"M_J_CPU0_SA_DQ<31:0>";
9"M_J_CPU0_SB_DQ<31:0>";
10"M_J_CPU0_SA_DQS_DN<9:0>";
11"M_J_CPU0_SA_DQS_DP<9:0>";
12"M_J_CPU0_SB_DQS_DP<9:0>";
13"M_J_CPU0_SB_DQS_DN<9:0>";
14"I3C_SPD_DDRJ_CPU0_SCL";
15"M_J_CPU0_ALERT_N";
16"M_J_CPU0_RESET_N";
17"M_J_CPU0_CLK_DN<0>";
18"M_J_CPU0_SB_CS_N<0>";
19"M_J_CPU0_SB_CS_N<1>";
20"M_J_CPU0_SA_DQ<10>";
21"M_J_CPU0_SA_DQ<11>";
22"M_J_CPU0_SA_DQ<12>";
23"M_J_CPU0_SA_DQ<13>";
24"M_J_CPU0_SA_DQ<14>";
25"M_J_CPU0_SB_CA<3>";
26"PWRGD_CHGL_CPU0";
27"M_J_CPU0_SB_DQ<22>";
28"M_J_CPU0_SB_DQ<24>";
29"M_J_CPU0_SB_DQ<26>";
30"M_J_CPU0_SB_DQ<27>";
31"M_J_CPU0_SA_DQ<30>";
32"M_J_CPU0_SB_RSP<0>";
33"M_J_CPU0_SA_DQ<26>";
34"M_J_CPU0_SB_DQ<23>";
35"M_J_CPU0_SA_CB<1>";
36"M_J_CPU0_SB_DQS_DP<9>";
37"M_J_CPU0_SB_DQS_DN<9>";
38"M_J_CPU0_SA_DQS_DP<9>";
39"M_J_CPU0_SA_DQS_DN<9>";
40"M_J_CPU0_SA_DQS_DP<8>";
41"M_J_CPU0_SA_DQS_DN<8>";
42"M_J_CPU0_SB_DQS_DN<7>";
43"M_J_CPU0_SA_DQS_DP<7>";
44"M_J_CPU0_SB_DQS_DP<6>";
45"M_J_CPU0_SB_DQS_DN<6>";
46"M_J_CPU0_SA_DQS_DN<6>";
47"M_J_CPU0_SB_DQS_DP<5>";
48"M_J_CPU0_SB_DQS_DN<5>";
49"M_J_CPU0_SA_DQS_DP<5>";
50"M_J_CPU0_SA_DQS_DN<5>";
51"M_J_CPU0_SB_DQS_DP<4>";
52"M_J_CPU0_SB_DQS_DN<4>";
53"M_J_CPU0_SA_DQS_DP<4>";
54"M_J_CPU0_SA_DQS_DN<4>";
55"M_J_CPU0_SB_DQS_DP<3>";
56"M_J_CPU0_SB_DQS_DN<3>";
57"M_J_CPU0_SA_DQS_DP<3>";
58"M_J_CPU0_SA_DQS_DN<3>";
59"M_J_CPU0_SB_DQS_DP<2>";
60"M_J_CPU0_SB_DQS_DN<2>";
61"M_J_CPU0_SA_DQS_DP<2>";
62"M_J_CPU0_SA_DQS_DN<2>";
63"M_J_CPU0_SB_DQS_DP<1>";
64"M_J_CPU0_SB_DQS_DN<1>";
65"M_J_CPU0_SA_DQS_DP<1>";
66"M_J_CPU0_SA_DQS_DN<1>";
67"M_J_CPU0_SB_DQS_DP<0>";
68"M_J_CPU0_SB_DQS_DN<0>";
69"M_J_CPU0_SA_DQS_DP<0>";
70"M_J_CPU0_SA_DQS_DN<0>";
71"M_J_CPU0_SB_DQS_DP<7>";
72"M_J_CPU0_SB_DQS_DN<8>";
73"M_J_CPU0_SB_DQS_DP<8>";
74"M_J_CPU0_SA_DQS_DP<6>";
75"M_J_CPU0_SA_DQS_DN<7>";
76"M_J_CPU0_SA_DQ<31>";
77"M_J_CPU0_SB_PAR";
78"M_J_CPU0_SA_PAR";
79"M_J_CPU0_SB_DQ<0>";
80"M_J_CPU0_SB_DQ<1>";
81"M_J_CPU0_SB_DQ<2>";
82"M_J_CPU0_SB_DQ<3>";
83"M_J_CPU0_SB_DQ<4>";
84"M_J_CPU0_SB_DQ<5>";
85"M_J_CPU0_SB_DQ<6>";
86"M_J_CPU0_SB_DQ<7>";
87"M_J_CPU0_SB_DQ<8>";
88"M_J_CPU0_SB_DQ<9>";
89"M_J_CPU0_SB_DQ<10>";
90"M_J_CPU0_SB_DQ<11>";
91"M_J_CPU0_SB_DQ<12>";
92"M_J_CPU0_SB_DQ<13>";
93"M_J_CPU0_SB_DQ<14>";
94"M_J_CPU0_SB_DQ<15>";
95"M_J_CPU0_SB_DQ<16>";
96"M_J_CPU0_SB_DQ<17>";
97"M_J_CPU0_SB_DQ<18>";
98"M_J_CPU0_SB_DQ<19>";
99"M_J_CPU0_SB_DQ<20>";
100"M_J_CPU0_SB_DQ<21>";
101"M_J_CPU0_SB_DQ<25>";
102"M_J_CPU0_SB_DQ<28>";
103"M_J_CPU0_SB_DQ<29>";
104"M_J_CPU0_SB_DQ<30>";
105"M_J_CPU0_SB_DQ<31>";
106"M_J_CPU0_SA_DQ<0>";
107"M_J_CPU0_SA_DQ<1>";
108"M_J_CPU0_SA_DQ<2>";
109"M_J_CPU0_SA_DQ<3>";
110"M_J_CPU0_SA_DQ<4>";
111"M_J_CPU0_SA_DQ<5>";
112"M_J_CPU0_SA_DQ<6>";
113"M_J_CPU0_SA_DQ<7>";
114"M_J_CPU0_SA_DQ<8>";
115"M_J_CPU0_SA_DQ<9>";
116"M_J_CPU0_SA_DQ<15>";
117"M_J_CPU0_SA_DQ<16>";
118"M_J_CPU0_SA_DQ<17>";
119"M_J_CPU0_SA_DQ<18>";
120"M_J_CPU0_SA_DQ<19>";
121"M_J_CPU0_SA_DQ<20>";
122"M_J_CPU0_SA_DQ<21>";
123"M_J_CPU0_SA_DQ<22>";
124"M_J_CPU0_SA_DQ<23>";
125"M_J_CPU0_SA_DQ<24>";
126"M_J_CPU0_SA_DQ<25>";
127"M_J_CPU0_SA_DQ<27>";
128"M_J_CPU0_SA_DQ<28>";
129"M_J_CPU0_SA_DQ<29>";
130"M_J_CPU0_SA_CS_N<1>";
131"M_J_CPU0_SA_CS_N<0>";
132"M_J_CPU0_CLK_DP<0>";
133"M_J_CPU0_SB_CB<0>";
134"M_J_CPU0_SB_CB<1>";
135"M_J_CPU0_SB_CB<2>";
136"M_J_CPU0_SB_CB<3>";
137"M_J_CPU0_SB_CB<4>";
138"M_J_CPU0_SA_CB<2>";
139"M_J_CPU0_SA_CB<3>";
140"M_J_CPU0_SA_CB<5>";
141"M_J_CPU0_SA_CB<6>";
142"M_J_CPU0_SB_CA<6>";
143"M_J_CPU0_SA_CA<6>";
144"M_J_CPU0_SB_CA<5>";
145"M_J_CPU0_SA_CA<5>";
146"M_J_CPU0_SB_CA<4>";
147"M_J_CPU0_SA_CA<4>";
148"M_J_CPU0_SA_CA<3>";
149"M_J_CPU0_SB_CA<2>";
150"M_J_CPU0_SA_CA<2>";
151"M_J_CPU0_SB_CA<1>";
152"M_J_CPU0_SA_CA<1>";
153"M_J_CPU0_SB_CA<0>";
154"M_J_CPU0_SA_CA<0>";
155"M_J_CPU0_SB_CB<7>";
156"M_J_CPU0_SA_CB<4>";
157"M_J_CPU0_SA_CB<7>";
158"PD_CHJ_CPU0_DIMM_SAA";
159"M_J_CPU0_SA_CB<0>";
160"M_J_CPU0_SB_CB<6>";
161"M_J_CPU0_SB_CB<5>";
162"M_J_CPU0_SA_RSP<0>";
163"PD_CHJ_CPU0_DIMM_SAA";
164"PWRGD_CHJ_CPU0_DIMM";
165"I3C_SPD_DDRGL_CPU0_SCL";
166"P3V3_AUX\g";
167"P12V_MEM_CPU0\g";
168"GND\g";
169"GND\g";
170"GND\g";
171"I3C_SPD_DDRJ_CPU0_SDA";
172"I3C_SPD_DDRGL_CPU0_SDA";
%"TAP"
"1","(-5950,4075)","0","mstr_standard","I100";
;
CDS_LIB"mstr_standard"
BODY_TYPE"PLUMBING"
HDL_TAP"TRUE";
"B \NAC \NWC"8;
"S \NAC"
BN"6"112;
%"TAP"
"1","(-5950,4125)","0","mstr_standard","I101";
;
CDS_LIB"mstr_standard"
BODY_TYPE"PLUMBING"
HDL_TAP"TRUE";
"B \NAC \NWC"8;
"S \NAC"
BN"7"113;
%"TAP"
"1","(-5950,4275)","0","mstr_standard","I102";
;
CDS_LIB"mstr_standard"
BODY_TYPE"PLUMBING"
HDL_TAP"TRUE";
"B \NAC \NWC"8;
"S \NAC"
BN"10"20;
%"TAP"
"1","(-5950,4225)","0","mstr_standard","I103";
;
CDS_LIB"mstr_standard"
BODY_TYPE"PLUMBING"
HDL_TAP"TRUE";
"B \NAC \NWC"8;
"S \NAC"
BN"9"115;
%"TAP"
"1","(-5950,4175)","0","mstr_standard","I104";
;
CDS_LIB"mstr_standard"
BODY_TYPE"PLUMBING"
HDL_TAP"TRUE";
"B \NAC \NWC"8;
"S \NAC"
BN"8"114;
%"TAP"
"1","(-5950,4325)","0","mstr_standard","I105";
;
CDS_LIB"mstr_standard"
BODY_TYPE"PLUMBING"
HDL_TAP"TRUE";
"B \NAC \NWC"8;
"S \NAC"
BN"11"21;
%"TAP"
"1","(-5950,4375)","0","mstr_standard","I106";
;
CDS_LIB"mstr_standard"
BODY_TYPE"PLUMBING"
HDL_TAP"TRUE";
"B \NAC \NWC"8;
"S \NAC"
BN"12"22;
%"TAP"
"1","(-5950,4425)","0","mstr_standard","I107";
;
CDS_LIB"mstr_standard"
BODY_TYPE"PLUMBING"
HDL_TAP"TRUE";
"B \NAC \NWC"8;
"S \NAC"
BN"13"23;
%"TAP"
"1","(-5950,4475)","0","mstr_standard","I108";
;
CDS_LIB"mstr_standard"
BODY_TYPE"PLUMBING"
HDL_TAP"TRUE";
"B \NAC \NWC"8;
"S \NAC"
BN"14"24;
%"TAP"
"1","(-5950,4525)","0","mstr_standard","I109";
;
CDS_LIB"mstr_standard"
BODY_TYPE"PLUMBING"
HDL_TAP"TRUE";
"B \NAC \NWC"8;
"S \NAC"
BN"15"116;
%"TAP"
"1","(-5950,4625)","0","mstr_standard","I110";
;
CDS_LIB"mstr_standard"
BODY_TYPE"PLUMBING"
HDL_TAP"TRUE";
"B \NAC \NWC"8;
"S \NAC"
BN"17"118;
%"TAP"
"1","(-5950,4575)","0","mstr_standard","I111";
;
CDS_LIB"mstr_standard"
BODY_TYPE"PLUMBING"
HDL_TAP"TRUE";
"B \NAC \NWC"8;
"S \NAC"
BN"16"117;
%"TAP"
"1","(-5950,4775)","0","mstr_standard","I112";
;
CDS_LIB"mstr_standard"
BODY_TYPE"PLUMBING"
HDL_TAP"TRUE";
"B \NAC \NWC"8;
"S \NAC"
BN"20"121;
%"TAP"
"1","(-5950,4725)","0","mstr_standard","I113";
;
CDS_LIB"mstr_standard"
BODY_TYPE"PLUMBING"
HDL_TAP"TRUE";
"B \NAC \NWC"8;
"S \NAC"
BN"19"120;
%"TAP"
"1","(-5950,4675)","0","mstr_standard","I114";
;
CDS_LIB"mstr_standard"
BODY_TYPE"PLUMBING"
HDL_TAP"TRUE";
"B \NAC \NWC"8;
"S \NAC"
BN"18"119;
%"TAP"
"1","(-5950,4875)","0","mstr_standard","I115";
;
CDS_LIB"mstr_standard"
BODY_TYPE"PLUMBING"
HDL_TAP"TRUE";
"B \NAC \NWC"8;
"S \NAC"
BN"22"123;
%"TAP"
"1","(-5950,4825)","0","mstr_standard","I116";
;
CDS_LIB"mstr_standard"
BODY_TYPE"PLUMBING"
HDL_TAP"TRUE";
"B \NAC \NWC"8;
"S \NAC"
BN"21"122;
%"TAP"
"1","(-5950,5025)","0","mstr_standard","I117";
;
CDS_LIB"mstr_standard"
BODY_TYPE"PLUMBING"
HDL_TAP"TRUE";
"B \NAC \NWC"8;
"S \NAC"
BN"25"126;
%"TAP"
"1","(-5950,4975)","0","mstr_standard","I118";
;
CDS_LIB"mstr_standard"
BODY_TYPE"PLUMBING"
HDL_TAP"TRUE";
"B \NAC \NWC"8;
"S \NAC"
BN"24"125;
%"TAP"
"1","(-5950,4925)","0","mstr_standard","I119";
;
CDS_LIB"mstr_standard"
BODY_TYPE"PLUMBING"
HDL_TAP"TRUE";
"B \NAC \NWC"8;
"S \NAC"
BN"23"124;
%"TAP"
"1","(-5950,5125)","0","mstr_standard","I120";
;
CDS_LIB"mstr_standard"
BODY_TYPE"PLUMBING"
HDL_TAP"TRUE";
"B \NAC \NWC"8;
"S \NAC"
BN"27"127;
%"TAP"
"1","(-5950,5175)","0","mstr_standard","I121";
;
CDS_LIB"mstr_standard"
BODY_TYPE"PLUMBING"
HDL_TAP"TRUE";
"B \NAC \NWC"8;
"S \NAC"
BN"28"128;
%"TAP"
"1","(-5950,5075)","0","mstr_standard","I122";
;
CDS_LIB"mstr_standard"
BODY_TYPE"PLUMBING"
HDL_TAP"TRUE";
"B \NAC \NWC"8;
"S \NAC"
BN"26"33;
%"TAP"
"1","(-5950,5275)","0","mstr_standard","I123";
;
CDS_LIB"mstr_standard"
BODY_TYPE"PLUMBING"
HDL_TAP"TRUE";
"B \NAC \NWC"8;
"S \NAC"
BN"30"31;
%"TAP"
"1","(-5950,5225)","0","mstr_standard","I124";
;
CDS_LIB"mstr_standard"
BODY_TYPE"PLUMBING"
HDL_TAP"TRUE";
"B \NAC \NWC"8;
"S \NAC"
BN"29"129;
%"TAP"
"1","(-5950,5325)","0","mstr_standard","I125";
;
CDS_LIB"mstr_standard"
BODY_TYPE"PLUMBING"
HDL_TAP"TRUE";
"B \NAC \NWC"8;
"S \NAC"
BN"31"76;
%"GND"
"1","(-6350,950)","0","mstr_symbols","I128";
;
SIZE"1B"
BOM_COST"MEM"
CDS_LIB"mstr_symbols"
VOLTAGE"0.0"
BODY_TYPE"PLUMBING"
HDL_POWER"GND";
"A\NAC"1;
%"Q_RES"
"2","(-6350,1175)","0","pure_quanta","I129";
;
LOCATION"R767"
$SEC"1"
CDS_SEC"1"
WATTAGE"1/16W"
MATERIAL"CHIP"
TOLERANCE"1%"
VALUE"35.7K"
PACK_TYPE"0402LF"
CDS_LIB"pure_quanta"
PART_NUMBER"CS33572FB01";
"A"
$PN"1"158;
"B"
$PN"2"1;
%"GND"
"1","(-2050,1850)","0","mstr_symbols","I141";
;
SIZE"1B"
CDS_LIB"mstr_symbols"
VOLTAGE"0.0"
BODY_TYPE"PLUMBING"
HDL_POWER"GND";
"A\NAC"170;
%"GND"
"1","(-250,1625)","0","mstr_symbols","I142";
;
CDS_LIB"mstr_symbols"
SIZE"1B"
VOLTAGE"0.0"
BODY_TYPE"PLUMBING"
HDL_POWER"GND";
"A\NAC"169;
%"SCONN288_DDR506112002KQ"
"3","(-1150,3625)","0","pure_quanta","I177";
;
LOCATION"J68"
$SEC"3"
CDS_SEC"3"
PART_TYPE"SMLF"
MATERIAL"IO"
VALUE"SCONN288_DDR506112002KQ"
CDS_LMAN_SYM_OUTLINE"-450,1800,450,-1750"
NEEDS_NO_SIZE"TRUE"
CDS_LIB"pure_quanta"
PART_NUMBER"DFHST8FS479";
"G3"
$PN"G3"169;
"G2"
$PN"G2"169;
"G1"
$PN"G1"169;
"VSS62"
$PN"141"169;
"VSS61"
$PN"139"169;
"VSS60"
$PN"136"169;
"VSS58"
$PN"132"169;
"VSS104"
$PN"240"170;
"VSS102"
$PN"235"170;
"VSS100"
$PN"230"170;
"VIN_BULK2"
$PN"146"167;
"VIN_BULK1"
$PN"145"167;
"VIN_BULK0"
$PN"1"167;
"VSS126"
$PN"288"170;
"VSS125"
$PN"286"170;
"VSS124"
$PN"284"170;
"VSS123"
$PN"281"170;
"VSS122"
$PN"279"170;
"VSS121"
$PN"277"170;
"VSS120"
$PN"275"170;
"VSS119"
$PN"273"170;
"VSS118"
$PN"270"170;
"VSS117"
$PN"268"170;
"VSS116"
$PN"266"170;
"VSS115"
$PN"264"170;
"VSS114"
$PN"262"170;
"VSS113"
$PN"259"170;
"VSS112"
$PN"257"170;
"VSS111"
$PN"255"170;
"VSS110"
$PN"253"170;
"VSS109"
$PN"251"170;
"VSS108"
$PN"248"170;
"VSS107"
$PN"246"170;
"VSS106"
$PN"244"170;
"VSS105"
$PN"242"170;
"VSS103"
$PN"237"170;
"VSS101"
$PN"233"170;
"VSS99"
$PN"228"170;
"VSS98"
$PN"226"170;
"VSS97"
$PN"224"170;
"VSS96"
$PN"222"170;
"VSS95"
$PN"219"170;
"VSS94"
$PN"216"170;
"VSS93"
$PN"214"170;
"VSS92"
$PN"212"170;
"VSS91"
$PN"210"170;
"VSS90"
$PN"208"170;
"VSS89"
$PN"206"170;
"VSS88"
$PN"204"170;
"VSS87"
$PN"202"170;
"VSS86"
$PN"199"170;
"VSS85"
$PN"197"170;
"VSS84"
$PN"195"170;
"VSS83"
$PN"193"170;
"VSS82"
$PN"191"170;
"VSS81"
$PN"188"170;
"VSS80"
$PN"186"170;
"VSS79"
$PN"184"170;
"VSS78"
$PN"182"170;
"VSS77"
$PN"180"170;
"VSS76"
$PN"177"170;
"VSS75"
$PN"175"170;
"VSS74"
$PN"173"170;
"VSS73"
$PN"171"170;
"VSS72"
$PN"169"170;
"VSS71"
$PN"166"170;
"VSS70"
$PN"164"170;
"VSS69"
$PN"162"170;
"VSS68"
$PN"160"170;
"VSS67"
$PN"158"170;
"VSS66"
$PN"155"170;
"VSS65"
$PN"153"170;
"VSS64"
$PN"151"170;
"VSS63"
$PN"143"169;
"VSS59"
$PN"134"169;
"VSS57"
$PN"130"169;
"VSS56"
$PN"128"169;
"VSS55"
$PN"125"169;
"VSS54"
$PN"123"169;
"VSS53"
$PN"121"169;
"VSS52"
$PN"119"169;
"VSS51"
$PN"117"169;
"VSS50"
$PN"114"169;
"VSS49"
$PN"112"169;
"VSS48"
$PN"110"169;
"VSS47"
$PN"108"169;
"VSS46"
$PN"106"169;
"VSS45"
$PN"103"169;
"VSS44"
$PN"101"169;
"VSS43"
$PN"99"169;
"VSS42"
$PN"97"169;
"VSS41"
$PN"95"169;
"VSS40"
$PN"92"169;
"VSS39"
$PN"90"169;
"VSS38"
$PN"88"169;
"VSS37"
$PN"85"169;
"VSS36"
$PN"83"169;
"VSS35"
$PN"81"169;
"VSS34"
$PN"79"169;
"VSS33"
$PN"77"169;
"VSS32"
$PN"75"169;
"VSS31"
$PN"73"169;
"VSS30"
$PN"71"169;
"VSS29"
$PN"69"169;
"VSS28"
$PN"67"169;
"VSS27"
$PN"65"169;
"VSS26"
$PN"63"169;
"VSS25"
$PN"61"169;
"VSS24"
$PN"59"169;
"VSS23"
$PN"57"169;
"VSS22"
$PN"54"169;
"VSS21"
$PN"52"169;
"VSS20"
$PN"50"169;
"VSS19"
$PN"48"169;
"VSS18"
$PN"46"169;
"VSS17"
$PN"43"169;
"VSS16"
$PN"41"169;
"VSS15"
$PN"39"169;
"VSS14"
$PN"37"169;
"VSS13"
$PN"35"169;
"VSS12"
$PN"32"169;
"VSS11"
$PN"30"169;
"VSS10"
$PN"28"169;
"VSS9"
$PN"26"169;
"VSS8"
$PN"24"169;
"VSS7"
$PN"21"169;
"VSS6"
$PN"19"169;
"VSS5"
$PN"17"169;
"VSS4"
$PN"15"169;
"VSS3"
$PN"13"169;
"VSS2"
$PN"10"169;
"VSS1"
$PN"8"169;
"VSS0"
$PN"6"169;
%"Q_CAP"
"1","(-8550,3175)","2","pure_quanta","I185";
;
LOCATION"C124"
$SEC"1"
CDS_SEC"1"
PACK_TYPE"0402"
VOLTAGE"25V"
VALUE"0.1UF"
TOLERANCE"10%"
MATERIAL"X7R"
CDS_LIB"pure_quanta"
BOM_COST"MEM"
ROOM""
PART_NUMBER"CH4104K1B00";
"B"
$PN"2"2;
"A"
$PN"1"166;
%"GND"
"1","(-8550,2950)","0","mstr_symbols","I186";
;
BOM_COST"MEM"
SIZE"1B"
CDS_LIB"mstr_symbols"
VOLTAGE"0"
ROOM"MEM_EFGH_DECOUPLING_CAPS"
BODY_TYPE"PLUMBING"
HDL_POWER"GND";
"A\NAC"2;
%"Q_RES"
"1","(-8450,2075)","2","pure_quanta","I188";
;
LOCATION"R300"
$SEC"1"
CDS_SEC"1"
VALUE"1K"
TOLERANCE"1%"
CDS_LIB"pure_quanta"
BOM_COST"MEM"
WATTAGE"1/16W"
MATERIAL"CHIP"
PACK_TYPE"0402LF"
ROOM""
PART_NUMBER"CS21002FB06";
"B"
$PN"2"26;
"A"
$PN"1"164;
%"Q_RES"
"2","(-8325,2225)","0","pure_quanta","I189";
;
LOCATION"R99"
$SEC"1"
CDS_SEC"1"
TOLERANCE"1%"
WATTAGE"1/16W"
MATERIAL"EMPTY"
VALUE"1K"
PACK_TYPE"0402LF"
CDS_LIB"pure_quanta"
BOM_COST"MEM"
ROOM""
PART_NUMBER"CS21002FB06";
"A"
$PN"1"3;
"B"
$PN"2"164;
%"VCC_CORE"
"1","(-8325,2400)","0","mstr_symbols","I190";
;
HDL_POWER"P3V3"
CDS_LIB"mstr_symbols"
VOLTAGE"3.3"
ROOM"PVCCINFAON_CPU0_CTRL";
"A"3;
%"TAP"
"1","(-3175,4075)","0","mstr_standard","I196";
;
CDS_LIB"mstr_standard"
BODY_TYPE"PLUMBING"
HDL_TAP"TRUE";
"B \NAC \NWC"10;
"S \NAC"
BN"8"41;
%"TAP"
"1","(-3175,4175)","0","mstr_standard","I197";
;
CDS_LIB"mstr_standard"
BODY_TYPE"PLUMBING"
HDL_TAP"TRUE";
"B \NAC \NWC"10;
"S \NAC"
BN"9"39;
%"TAP"
"1","(-3375,4225)","0","mstr_standard","I198";
;
CDS_LIB"mstr_standard"
BODY_TYPE"PLUMBING"
HDL_TAP"TRUE";
"B \NAC \NWC"11;
"S \NAC"
BN"9"38;
%"TAP"
"1","(-3375,4125)","0","mstr_standard","I199";
;
CDS_LIB"mstr_standard"
BODY_TYPE"PLUMBING"
HDL_TAP"TRUE";
"B \NAC \NWC"11;
"S \NAC"
BN"8"40;
%"TAP"
"1","(-3175,3975)","0","mstr_standard","I200";
;
CDS_LIB"mstr_standard"
BODY_TYPE"PLUMBING"
HDL_TAP"TRUE";
"B \NAC \NWC"10;
"S \NAC"
BN"7"75;
%"TAP"
"1","(-3175,3875)","0","mstr_standard","I201";
;
CDS_LIB"mstr_standard"
BODY_TYPE"PLUMBING"
HDL_TAP"TRUE";
"B \NAC \NWC"10;
"S \NAC"
BN"6"46;
%"TAP"
"1","(-3175,3775)","0","mstr_standard","I202";
;
CDS_LIB"mstr_standard"
BODY_TYPE"PLUMBING"
HDL_TAP"TRUE";
"B \NAC \NWC"10;
"S \NAC"
BN"5"50;
%"TAP"
"1","(-3175,3675)","0","mstr_standard","I203";
;
CDS_LIB"mstr_standard"
BODY_TYPE"PLUMBING"
HDL_TAP"TRUE";
"B \NAC \NWC"10;
"S \NAC"
BN"4"54;
%"TAP"
"1","(-3175,3575)","0","mstr_standard","I204";
;
CDS_LIB"mstr_standard"
BODY_TYPE"PLUMBING"
HDL_TAP"TRUE";
"B \NAC \NWC"10;
"S \NAC"
BN"3"58;
%"TAP"
"1","(-3175,3475)","0","mstr_standard","I205";
;
CDS_LIB"mstr_standard"
BODY_TYPE"PLUMBING"
HDL_TAP"TRUE";
"B \NAC \NWC"10;
"S \NAC"
BN"2"62;
%"TAP"
"1","(-3175,3375)","0","mstr_standard","I206";
;
CDS_LIB"mstr_standard"
BODY_TYPE"PLUMBING"
HDL_TAP"TRUE";
"B \NAC \NWC"10;
"S \NAC"
BN"1"66;
%"TAP"
"1","(-3175,3275)","0","mstr_standard","I207";
;
CDS_LIB"mstr_standard"
BODY_TYPE"PLUMBING"
HDL_TAP"TRUE";
"B \NAC \NWC"10;
"S \NAC"
BN"0"70;
%"TAP"
"1","(-3175,3125)","0","mstr_standard","I208";
;
CDS_LIB"mstr_standard"
BODY_TYPE"PLUMBING"
HDL_TAP"TRUE";
"B \NAC \NWC"13;
"S \NAC"
BN"9"37;
%"TAP"
"1","(-3375,4025)","0","mstr_standard","I209";
;
CDS_LIB"mstr_standard"
BODY_TYPE"PLUMBING"
HDL_TAP"TRUE";
"B \NAC \NWC"11;
"S \NAC"
BN"7"43;
%"TAP"
"1","(-3375,3925)","0","mstr_standard","I210";
;
CDS_LIB"mstr_standard"
BODY_TYPE"PLUMBING"
HDL_TAP"TRUE";
"B \NAC \NWC"11;
"S \NAC"
BN"6"74;
%"TAP"
"1","(-3375,3825)","0","mstr_standard","I211";
;
CDS_LIB"mstr_standard"
BODY_TYPE"PLUMBING"
HDL_TAP"TRUE";
"B \NAC \NWC"11;
"S \NAC"
BN"5"49;
%"TAP"
"1","(-3375,3725)","0","mstr_standard","I212";
;
CDS_LIB"mstr_standard"
BODY_TYPE"PLUMBING"
HDL_TAP"TRUE";
"B \NAC \NWC"11;
"S \NAC"
BN"4"53;
%"TAP"
"1","(-3375,3625)","0","mstr_standard","I213";
;
CDS_LIB"mstr_standard"
BODY_TYPE"PLUMBING"
HDL_TAP"TRUE";
"B \NAC \NWC"11;
"S \NAC"
BN"3"57;
%"TAP"
"1","(-3375,3525)","0","mstr_standard","I214";
;
CDS_LIB"mstr_standard"
BODY_TYPE"PLUMBING"
HDL_TAP"TRUE";
"B \NAC \NWC"11;
"S \NAC"
BN"2"61;
%"TAP"
"1","(-3375,3425)","0","mstr_standard","I215";
;
CDS_LIB"mstr_standard"
BODY_TYPE"PLUMBING"
HDL_TAP"TRUE";
"B \NAC \NWC"11;
"S \NAC"
BN"1"65;
%"TAP"
"1","(-3375,3325)","0","mstr_standard","I216";
;
CDS_LIB"mstr_standard"
BODY_TYPE"PLUMBING"
HDL_TAP"TRUE";
"B \NAC \NWC"11;
"S \NAC"
BN"0"69;
%"TAP"
"1","(-3375,3175)","0","mstr_standard","I217";
;
CDS_LIB"mstr_standard"
BODY_TYPE"PLUMBING"
HDL_TAP"TRUE";
"B \NAC \NWC"12;
"S \NAC"
BN"9"36;
%"TAP"
"1","(-3375,3075)","0","mstr_standard","I218";
;
CDS_LIB"mstr_standard"
BODY_TYPE"PLUMBING"
HDL_TAP"TRUE";
"B \NAC \NWC"12;
"S \NAC"
BN"8"73;
%"TAP"
"1","(-3175,2925)","0","mstr_standard","I219";
;
CDS_LIB"mstr_standard"
BODY_TYPE"PLUMBING"
HDL_TAP"TRUE";
"B \NAC \NWC"13;
"S \NAC"
BN"7"42;
%"SCONN288_DDR506112002KQ"
"1","(-6800,3575)","0","pure_quanta","I22";
;
LOCATION"J68"
$SEC"1"
CDS_SEC"1"
MATERIAL"IO"
VALUE"SCONN288_DDR506112002KQ"
PART_TYPE"SMLF"
CDS_LMAN_SYM_OUTLINE"-450,1900,450,-1850"
NEEDS_NO_SIZE"TRUE"
CDS_LIB"pure_quanta"
PART_NUMBER"DFHST8FS479";
"PWR_GOOD||FAIL_N"
$PN"147"164;
"DQ31_A"
$PN"194"76;
"CB7_A"
$PN"205"157;
"CB4_A"
$PN"58"156;
"CB1_A"
$PN"53"35;
"CB7_B"
$PN"236"155;
"ALERT_N \B"
$PN"62"15;
"CA0_A"
$PN"66"154;
"CA0_B"
$PN"76"153;
"CA1_A"
$PN"211"152;
"CA1_B"
$PN"221"151;
"CA2_A"
$PN"68"150;
"CA2_B"
$PN"78"149;
"CA3_A"
$PN"213"148;
"CA3_B"
$PN"223"25;
"CA4_A"
$PN"70"147;
"CA4_B"
$PN"80"146;
"CA5_A"
$PN"215"145;
"CA5_B"
$PN"225"144;
"CA6_A"
$PN"72"143;
"CA6_B"
$PN"82"142;
"CB6_A"
$PN"203"141;
"CB5_A"
$PN"60"140;
"CB3_A"
$PN"198"139;
"CB2_A"
$PN"196"138;
"CB0_A"
$PN"51"159;
"CB6_B"
$PN"234"160;
"CB5_B"
$PN"91"161;
"CB4_B"
$PN"89"137;
"CB3_B"
$PN"243"136;
"CB2_B"
$PN"241"135;
"CB1_B"
$PN"98"134;
"CB0_B"
$PN"96"133;
"CK_C \B"
$PN"218"17;
"CK_T"
$PN"217"132;
"CS0_A_N"
$PN"64"131;
"CS0_B_N"
$PN"84"18;
"CS1_A_N"
$PN"209"130;
"CS1_B_N"
$PN"229"19;
"DQ30_A"
$PN"192"31;
"DQ29_A"
$PN"49"129;
"DQ28_A"
$PN"47"128;
"DQ27_A"
$PN"187"127;
"DQ26_A"
$PN"185"33;
"DQ25_A"
$PN"42"126;
"DQ24_A"
$PN"40"125;
"DQ23_A"
$PN"183"124;
"DQ22_A"
$PN"181"123;
"DQ21_A"
$PN"38"122;
"DQ20_A"
$PN"36"121;
"DQ19_A"
$PN"176"120;
"DQ18_A"
$PN"174"119;
"DQ17_A"
$PN"31"118;
"DQ16_A"
$PN"29"117;
"DQ15_A"
$PN"172"116;
"DQ14_A"
$PN"170"24;
"DQ13_A"
$PN"27"23;
"DQ12_A"
$PN"25"22;
"DQ11_A"
$PN"165"21;
"DQ10_A"
$PN"163"20;
"DQ9_A"
$PN"20"115;
"DQ8_A"
$PN"18"114;
"DQ7_A"
$PN"161"113;
"DQ6_A"
$PN"159"112;
"DQ5_A"
$PN"16"111;
"DQ4_A"
$PN"14"110;
"DQ3_A"
$PN"154"109;
"DQ2_A"
$PN"152"108;
"DQ1_A"
$PN"9"107;
"DQ0_A"
$PN"7"106;
"DQ31_B"
$PN"287"105;
"DQ30_B"
$PN"285"104;
"DQ29_B"
$PN"142"103;
"DQ28_B"
$PN"140"102;
"DQ27_B"
$PN"280"30;
"DQ26_B"
$PN"278"29;
"DQ25_B"
$PN"135"101;
"DQ24_B"
$PN"133"28;
"DQ23_B"
$PN"276"34;
"DQ22_B"
$PN"274"27;
"DQ21_B"
$PN"131"100;
"DQ20_B"
$PN"129"99;
"DQ19_B"
$PN"269"98;
"DQ18_B"
$PN"267"97;
"DQ17_B"
$PN"124"96;
"DQ16_B"
$PN"122"95;
"DQ15_B"
$PN"265"94;
"DQ14_B"
$PN"263"93;
"DQ13_B"
$PN"120"92;
"DQ12_B"
$PN"118"91;
"DQ11_B"
$PN"258"90;
"DQ10_B"
$PN"256"89;
"DQ9_B"
$PN"113"88;
"DQ8_B"
$PN"111"87;
"DQ7_B"
$PN"254"86;
"DQ6_B"
$PN"252"85;
"DQ5_B"
$PN"109"84;
"DQ4_B"
$PN"107"83;
"DQ3_B"
$PN"247"82;
"DQ2_B"
$PN"245"81;
"DQ1_B"
$PN"102"80;
"DQ0_B"
$PN"100"79;
"HAS"
$PN"148"163;
"HSCL"
$PN"4"14;
"HSDA"
$PN"5"171;
"LBD||RSP_A_N"
$PN"86"162;
"LBS||RSP_B_N"
$PN"87"32;
"PAR_A"
$PN"74"78;
"PAR_B"
$PN"227"77;
"RESET_N \B"
$PN"207"16;
"RFU6"
$PN"232"0;
"RFU5"
$PN"231"0;
"RFU4"
$PN"220"0;
"RFU3"
$PN"150"0;
"RFU2"
$PN"149"0;
"RFU1"
$PN"144"0;
"RFU0"
$PN"2"0;
"VIN_MGMT"
$PN"3"166;
%"TAP"
"1","(-3175,3025)","0","mstr_standard","I220";
;
CDS_LIB"mstr_standard"
BODY_TYPE"PLUMBING"
HDL_TAP"TRUE";
"B \NAC \NWC"13;
"S \NAC"
BN"8"72;
%"TAP"
"1","(-3175,2825)","0","mstr_standard","I221";
;
CDS_LIB"mstr_standard"
BODY_TYPE"PLUMBING"
HDL_TAP"TRUE";
"B \NAC \NWC"13;
"S \NAC"
BN"6"45;
%"TAP"
"1","(-3175,2625)","0","mstr_standard","I222";
;
CDS_LIB"mstr_standard"
BODY_TYPE"PLUMBING"
HDL_TAP"TRUE";
"B \NAC \NWC"13;
"S \NAC"
BN"4"52;
%"TAP"
"1","(-3175,2725)","0","mstr_standard","I223";
;
CDS_LIB"mstr_standard"
BODY_TYPE"PLUMBING"
HDL_TAP"TRUE";
"B \NAC \NWC"13;
"S \NAC"
BN"5"48;
%"TAP"
"1","(-3175,2525)","0","mstr_standard","I224";
;
CDS_LIB"mstr_standard"
BODY_TYPE"PLUMBING"
HDL_TAP"TRUE";
"B \NAC \NWC"13;
"S \NAC"
BN"3"56;
%"TAP"
"1","(-3175,2325)","0","mstr_standard","I225";
;
CDS_LIB"mstr_standard"
BODY_TYPE"PLUMBING"
HDL_TAP"TRUE";
"B \NAC \NWC"13;
"S \NAC"
BN"1"64;
%"TAP"
"1","(-3175,2425)","0","mstr_standard","I226";
;
CDS_LIB"mstr_standard"
BODY_TYPE"PLUMBING"
HDL_TAP"TRUE";
"B \NAC \NWC"13;
"S \NAC"
BN"2"60;
%"TAP"
"1","(-3175,2225)","0","mstr_standard","I227";
;
CDS_LIB"mstr_standard"
BODY_TYPE"PLUMBING"
HDL_TAP"TRUE";
"B \NAC \NWC"13;
"S \NAC"
BN"0"68;
%"TAP"
"1","(-3375,2975)","0","mstr_standard","I228";
;
CDS_LIB"mstr_standard"
BODY_TYPE"PLUMBING"
HDL_TAP"TRUE";
"B \NAC \NWC"12;
"S \NAC"
BN"7"71;
%"TAP"
"1","(-3375,2875)","0","mstr_standard","I229";
;
CDS_LIB"mstr_standard"
BODY_TYPE"PLUMBING"
HDL_TAP"TRUE";
"B \NAC \NWC"12;
"S \NAC"
BN"6"44;
%"TAP"
"1","(-7650,3125)","2","mstr_standard","I23";
;
CDS_LIB"mstr_standard"
BODY_TYPE"PLUMBING"
HDL_TAP"TRUE";
"B \NAC \NWC"4;
"S \NAC"
BN"0"133;
%"TAP"
"1","(-3375,2675)","0","mstr_standard","I230";
;
CDS_LIB"mstr_standard"
BODY_TYPE"PLUMBING"
HDL_TAP"TRUE";
"B \NAC \NWC"12;
"S \NAC"
BN"4"51;
%"TAP"
"1","(-3375,2775)","0","mstr_standard","I231";
;
CDS_LIB"mstr_standard"
BODY_TYPE"PLUMBING"
HDL_TAP"TRUE";
"B \NAC \NWC"12;
"S \NAC"
BN"5"47;
%"TAP"
"1","(-3375,2575)","0","mstr_standard","I232";
;
CDS_LIB"mstr_standard"
BODY_TYPE"PLUMBING"
HDL_TAP"TRUE";
"B \NAC \NWC"12;
"S \NAC"
BN"3"55;
%"TAP"
"1","(-3375,2475)","0","mstr_standard","I233";
;
CDS_LIB"mstr_standard"
BODY_TYPE"PLUMBING"
HDL_TAP"TRUE";
"B \NAC \NWC"12;
"S \NAC"
BN"2"59;
%"TAP"
"1","(-3375,2375)","0","mstr_standard","I234";
;
CDS_LIB"mstr_standard"
BODY_TYPE"PLUMBING"
HDL_TAP"TRUE";
"B \NAC \NWC"12;
"S \NAC"
BN"1"63;
%"TAP"
"1","(-3375,2275)","0","mstr_standard","I235";
;
CDS_LIB"mstr_standard"
BODY_TYPE"PLUMBING"
HDL_TAP"TRUE";
"B \NAC \NWC"12;
"S \NAC"
BN"0"67;
%"SCONN288_DDR506112002KQ"
"2","(-4325,3225)","0","pure_quanta","I236";
;
LOCATION"J68"
$SEC"2"
CDS_SEC"2"
MATERIAL"IO"
VALUE"SCONN288_DDR506112002KQ"
PART_TYPE"SMLF"
CDS_LMAN_SYM_OUTLINE"-600,1150,600,-1150"
NEEDS_NO_SIZE"TRUE"
CDS_LIB"pure_quanta"
PART_NUMBER"DFHST8FS479";
"DQS7_A_C||TDQS7_A_C \B"
$PN"178"75;
"DQS6_A_T||TDQS6_A_T"
$PN"168"74;
"DQS8_B_T||TDQS8_B_T"
$PN"283"73;
"DQS8_B_C||TDQS8_B_C \B"
$PN"282"72;
"DQS7_B_T||TDQS7_B_T"
$PN"272"71;
"DQS0_A_C \B"
$PN"12"70;
"DQS0_A_T"
$PN"11"69;
"DQS0_B_C \B"
$PN"105"68;
"DQS0_B_T"
$PN"104"67;
"DQS1_A_C \B"
$PN"23"66;
"DQS1_A_T"
$PN"22"65;
"DQS1_B_C \B"
$PN"116"64;
"DQS1_B_T"
$PN"115"63;
"DQS2_A_C \B"
$PN"34"62;
"DQS2_A_T"
$PN"33"61;
"DQS2_B_C \B"
$PN"127"60;
"DQS2_B_T"
$PN"126"59;
"DQS3_A_C \B"
$PN"45"58;
"DQS3_A_T"
$PN"44"57;
"DQS3_B_C \B"
$PN"138"56;
"DQS3_B_T"
$PN"137"55;
"DQS4_A_C \B"
$PN"56"54;
"DQS4_A_T"
$PN"55"53;
"DQS4_B_C \B"
$PN"238"52;
"DQS4_B_T"
$PN"239"51;
"DQS5_A_C||TDQS5_A_C||DQS5_A_T||TDQS5_A_T \B"
$PN"156"50;
"DQS5_A_T||TDQS5_A_T"
$PN"157"49;
"DQS5_B_C||TDQS5_B_C \B"
$PN"249"48;
"DQS5_B_T||TDQS5_B_T"
$PN"250"47;
"DQS6_A_C||TDQS6_A_C||DQS6_A_T||TDQS6_A_T \B"
$PN"167"46;
"DQS6_B_C||TDQS6_B_C \B"
$PN"260"45;
"DQS6_B_T||TDQS6_B_T"
$PN"261"44;
"DQS7_A_T||TDQS7_A_T"
$PN"179"43;
"DQS7_B_C||TDQS7_B_C \B"
$PN"271"42;
"DQS8_A_C||TDQS8_A_C \B"
$PN"189"41;
"DQS8_A_T||TDQS8_A_T"
$PN"190"40;
"DQS9_A_C||TDQS9_A_C \B"
$PN"200"39;
"DQS9_A_T||TDQS9_A_T"
$PN"201"38;
"DQS9_B_C||TDQS9_B_C \B"
$PN"94"37;
"DQS9_B_T||TDQS9_B_T||DBI4_B_N"
$PN"93"36;
%"GND"
"1","(-2750,5475)","0","pure_quanta_power","I237";
;
CDS_LIB"pure_quanta_power"
BOM_COST"MEM"
SIZE"1B"
ROOM"MEM_EFGH_DECOUPLING_CAPS"
HDL_POWER"GND";
"A<SIZE-1..0>\NAC"168;
%"Q_CAP"
"1","(-2750,5825)","2","pure_quanta","I238";
;
LOCATION"C165"
$SEC"1"
CDS_SEC"1"
PACK_TYPE"C0805"
VOLTAGE"25V"
VALUE"10UF"
TOLERANCE"10%"
MATERIAL"X6S"
CDS_LIB"pure_quanta"
BOM_COST"MEM"
ROOM""
PART_NUMBER"CH6104KEA00";
"B"
$PN"2"168;
"A"
$PN"1"167;
%"Q_CAP"
"1","(-2175,5825)","2","pure_quanta","I239";
;
LOCATION"C166"
$SEC"1"
CDS_SEC"1"
VOLTAGE"25V"
PACK_TYPE"C0805"
VALUE"10UF"
TOLERANCE"10%"
MATERIAL"X6S"
CDS_LIB"pure_quanta"
BOM_COST"MEM"
ROOM""
PART_NUMBER"CH6104KEA00";
"B"
$PN"2"168;
"A"
$PN"1"167;
%"TAP"
"1","(-7650,3175)","2","mstr_standard","I24";
;
CDS_LIB"mstr_standard"
BODY_TYPE"PLUMBING"
HDL_TAP"TRUE";
"B \NAC \NWC"4;
"S \NAC"
BN"1"134;
%"UNIVERSAL_POWER"
"1","(-2750,6150)","0","pure_quanta_power","I240";
;
HDL_POWER"P12V_MEM_CPU0"
BOM_COST"VR_SYSTEM"
CDS_LIB"pure_quanta_power";
"A"167;
%"Q_RES"
"1","(-7700,2550)","0","pure_quanta","I242";
;
LOCATION"R1577"
$SEC"1"
CDS_SEC"1"
VALUE"49.9"
TOLERANCE"1%"
WATTAGE"1/16W"
PACK_TYPE"0402LF"
MATERIAL"CHIP"
CDS_LIB"pure_quanta"
PART_NUMBER"CS04992FB07";
"B"
$PN"2"14;
"A"
$PN"1"165;
%"Q_RES"
"1","(-8100,2775)","0","pure_quanta","I243";
;
LOCATION"R1684"
$SEC"1"
CDS_SEC"1"
VALUE"10"
PACK_TYPE"0402LF"
MATERIAL"CHIP"
CDS_LIB"pure_quanta"
TOLERANCE"1%"
WATTAGE"1/16W"
PART_NUMBER"CS01002FB07";
"B"
$PN"2"171;
"A"
$PN"1"172;
%"TAP"
"1","(-7650,3225)","2","mstr_standard","I25";
;
CDS_LIB"mstr_standard"
BODY_TYPE"PLUMBING"
HDL_TAP"TRUE";
"B \NAC \NWC"4;
"S \NAC"
BN"2"135;
%"TAP"
"1","(-7650,3275)","2","mstr_standard","I26";
;
CDS_LIB"mstr_standard"
BODY_TYPE"PLUMBING"
HDL_TAP"TRUE";
"B \NAC \NWC"4;
"S \NAC"
BN"3"136;
%"TAP"
"1","(-7650,3325)","2","mstr_standard","I27";
;
CDS_LIB"mstr_standard"
BODY_TYPE"PLUMBING"
HDL_TAP"TRUE";
"B \NAC \NWC"4;
"S \NAC"
BN"4"137;
%"TAP"
"1","(-7650,3375)","2","mstr_standard","I28";
;
CDS_LIB"mstr_standard"
BODY_TYPE"PLUMBING"
HDL_TAP"TRUE";
"B \NAC \NWC"4;
"S \NAC"
BN"5"161;
%"TAP"
"1","(-7650,3425)","2","mstr_standard","I29";
;
CDS_LIB"mstr_standard"
BODY_TYPE"PLUMBING"
HDL_TAP"TRUE";
"B \NAC \NWC"4;
"S \NAC"
BN"6"160;
%"TAP"
"1","(-7650,3475)","2","mstr_standard","I30";
;
CDS_LIB"mstr_standard"
BODY_TYPE"PLUMBING"
HDL_TAP"TRUE";
"B \NAC \NWC"4;
"S \NAC"
BN"7"155;
%"TAP"
"1","(-7650,3575)","2","mstr_standard","I31";
;
CDS_LIB"mstr_standard"
BODY_TYPE"PLUMBING"
HDL_TAP"TRUE";
"B \NAC \NWC"5;
"S \NAC"
BN"0"159;
%"TAP"
"1","(-7650,3625)","2","mstr_standard","I32";
;
CDS_LIB"mstr_standard"
BODY_TYPE"PLUMBING"
HDL_TAP"TRUE";
"B \NAC \NWC"5;
"S \NAC"
BN"1"35;
%"TAP"
"1","(-7650,3725)","2","mstr_standard","I33";
;
CDS_LIB"mstr_standard"
BODY_TYPE"PLUMBING"
HDL_TAP"TRUE";
"B \NAC \NWC"5;
"S \NAC"
BN"3"139;
%"TAP"
"1","(-7650,3675)","2","mstr_standard","I34";
;
CDS_LIB"mstr_standard"
BODY_TYPE"PLUMBING"
HDL_TAP"TRUE";
"B \NAC \NWC"5;
"S \NAC"
BN"2"138;
%"TAP"
"1","(-5950,2125)","0","mstr_standard","I35";
;
CDS_LIB"mstr_standard"
BODY_TYPE"PLUMBING"
HDL_TAP"TRUE";
"B \NAC \NWC"9;
"S \NAC"
BN"0"79;
%"TAP"
"1","(-5950,2225)","0","mstr_standard","I36";
;
CDS_LIB"mstr_standard"
BODY_TYPE"PLUMBING"
HDL_TAP"TRUE";
"B \NAC \NWC"9;
"S \NAC"
BN"2"81;
%"TAP"
"1","(-5950,2175)","0","mstr_standard","I37";
;
CDS_LIB"mstr_standard"
BODY_TYPE"PLUMBING"
HDL_TAP"TRUE";
"B \NAC \NWC"9;
"S \NAC"
BN"1"80;
%"TAP"
"1","(-5950,2325)","0","mstr_standard","I38";
;
CDS_LIB"mstr_standard"
BODY_TYPE"PLUMBING"
HDL_TAP"TRUE";
"B \NAC \NWC"9;
"S \NAC"
BN"4"83;
%"TAP"
"1","(-5950,2275)","0","mstr_standard","I39";
;
CDS_LIB"mstr_standard"
BODY_TYPE"PLUMBING"
HDL_TAP"TRUE";
"B \NAC \NWC"9;
"S \NAC"
BN"3"82;
%"TAP"
"1","(-5950,2375)","0","mstr_standard","I40";
;
CDS_LIB"mstr_standard"
BODY_TYPE"PLUMBING"
HDL_TAP"TRUE";
"B \NAC \NWC"9;
"S \NAC"
BN"5"84;
%"TAP"
"1","(-5950,2425)","0","mstr_standard","I41";
;
CDS_LIB"mstr_standard"
BODY_TYPE"PLUMBING"
HDL_TAP"TRUE";
"B \NAC \NWC"9;
"S \NAC"
BN"6"85;
%"TAP"
"1","(-5950,2475)","0","mstr_standard","I42";
;
CDS_LIB"mstr_standard"
BODY_TYPE"PLUMBING"
HDL_TAP"TRUE";
"B \NAC \NWC"9;
"S \NAC"
BN"7"86;
%"TAP"
"1","(-5950,2575)","0","mstr_standard","I43";
;
CDS_LIB"mstr_standard"
BODY_TYPE"PLUMBING"
HDL_TAP"TRUE";
"B \NAC \NWC"9;
"S \NAC"
BN"9"88;
%"TAP"
"1","(-5950,2525)","0","mstr_standard","I44";
;
CDS_LIB"mstr_standard"
BODY_TYPE"PLUMBING"
HDL_TAP"TRUE";
"B \NAC \NWC"9;
"S \NAC"
BN"8"87;
%"TAP"
"1","(-5950,2625)","0","mstr_standard","I45";
;
CDS_LIB"mstr_standard"
BODY_TYPE"PLUMBING"
HDL_TAP"TRUE";
"B \NAC \NWC"9;
"S \NAC"
BN"10"89;
%"TAP"
"1","(-5950,2725)","0","mstr_standard","I46";
;
CDS_LIB"mstr_standard"
BODY_TYPE"PLUMBING"
HDL_TAP"TRUE";
"B \NAC \NWC"9;
"S \NAC"
BN"12"91;
%"TAP"
"1","(-5950,2675)","0","mstr_standard","I47";
;
CDS_LIB"mstr_standard"
BODY_TYPE"PLUMBING"
HDL_TAP"TRUE";
"B \NAC \NWC"9;
"S \NAC"
BN"11"90;
%"TAP"
"1","(-5950,2825)","0","mstr_standard","I48";
;
CDS_LIB"mstr_standard"
BODY_TYPE"PLUMBING"
HDL_TAP"TRUE";
"B \NAC \NWC"9;
"S \NAC"
BN"14"93;
%"TAP"
"1","(-5950,2775)","0","mstr_standard","I49";
;
CDS_LIB"mstr_standard"
BODY_TYPE"PLUMBING"
HDL_TAP"TRUE";
"B \NAC \NWC"9;
"S \NAC"
BN"13"92;
%"TAP"
"1","(-5950,2875)","0","mstr_standard","I50";
;
CDS_LIB"mstr_standard"
BODY_TYPE"PLUMBING"
HDL_TAP"TRUE";
"B \NAC \NWC"9;
"S \NAC"
BN"15"94;
%"TAP"
"1","(-5950,2975)","0","mstr_standard","I51";
;
CDS_LIB"mstr_standard"
BODY_TYPE"PLUMBING"
HDL_TAP"TRUE";
"B \NAC \NWC"9;
"S \NAC"
BN"17"96;
%"TAP"
"1","(-5950,2925)","0","mstr_standard","I52";
;
CDS_LIB"mstr_standard"
BODY_TYPE"PLUMBING"
HDL_TAP"TRUE";
"B \NAC \NWC"9;
"S \NAC"
BN"16"95;
%"TAP"
"1","(-5950,3125)","0","mstr_standard","I53";
;
CDS_LIB"mstr_standard"
BODY_TYPE"PLUMBING"
HDL_TAP"TRUE";
"B \NAC \NWC"9;
"S \NAC"
BN"20"99;
%"TAP"
"1","(-5950,3075)","0","mstr_standard","I54";
;
CDS_LIB"mstr_standard"
BODY_TYPE"PLUMBING"
HDL_TAP"TRUE";
"B \NAC \NWC"9;
"S \NAC"
BN"19"98;
%"TAP"
"1","(-5950,3025)","0","mstr_standard","I55";
;
CDS_LIB"mstr_standard"
BODY_TYPE"PLUMBING"
HDL_TAP"TRUE";
"B \NAC \NWC"9;
"S \NAC"
BN"18"97;
%"TAP"
"1","(-5950,3175)","0","mstr_standard","I56";
;
CDS_LIB"mstr_standard"
BODY_TYPE"PLUMBING"
HDL_TAP"TRUE";
"B \NAC \NWC"9;
"S \NAC"
BN"21"100;
%"TAP"
"1","(-5950,3225)","0","mstr_standard","I57";
;
CDS_LIB"mstr_standard"
BODY_TYPE"PLUMBING"
HDL_TAP"TRUE";
"B \NAC \NWC"9;
"S \NAC"
BN"22"27;
%"TAP"
"1","(-5950,3375)","0","mstr_standard","I58";
;
CDS_LIB"mstr_standard"
BODY_TYPE"PLUMBING"
HDL_TAP"TRUE";
"B \NAC \NWC"9;
"S \NAC"
BN"25"101;
%"TAP"
"1","(-5950,3325)","0","mstr_standard","I59";
;
CDS_LIB"mstr_standard"
BODY_TYPE"PLUMBING"
HDL_TAP"TRUE";
"B \NAC \NWC"9;
"S \NAC"
BN"24"28;
%"TAP"
"1","(-5950,3275)","0","mstr_standard","I60";
;
CDS_LIB"mstr_standard"
BODY_TYPE"PLUMBING"
HDL_TAP"TRUE";
"B \NAC \NWC"9;
"S \NAC"
BN"23"34;
%"TAP"
"1","(-5950,3425)","0","mstr_standard","I61";
;
CDS_LIB"mstr_standard"
BODY_TYPE"PLUMBING"
HDL_TAP"TRUE";
"B \NAC \NWC"9;
"S \NAC"
BN"26"29;
%"TAP"
"1","(-5950,3475)","0","mstr_standard","I62";
;
CDS_LIB"mstr_standard"
BODY_TYPE"PLUMBING"
HDL_TAP"TRUE";
"B \NAC \NWC"9;
"S \NAC"
BN"27"30;
%"TAP"
"1","(-5950,3625)","0","mstr_standard","I63";
;
CDS_LIB"mstr_standard"
BODY_TYPE"PLUMBING"
HDL_TAP"TRUE";
"B \NAC \NWC"9;
"S \NAC"
BN"30"104;
%"TAP"
"1","(-5950,3575)","0","mstr_standard","I64";
;
CDS_LIB"mstr_standard"
BODY_TYPE"PLUMBING"
HDL_TAP"TRUE";
"B \NAC \NWC"9;
"S \NAC"
BN"29"103;
%"TAP"
"1","(-5950,3525)","0","mstr_standard","I65";
;
CDS_LIB"mstr_standard"
BODY_TYPE"PLUMBING"
HDL_TAP"TRUE";
"B \NAC \NWC"9;
"S \NAC"
BN"28"102;
%"TAP"
"1","(-5950,3675)","0","mstr_standard","I66";
;
CDS_LIB"mstr_standard"
BODY_TYPE"PLUMBING"
HDL_TAP"TRUE";
"B \NAC \NWC"9;
"S \NAC"
BN"31"105;
%"TAP"
"1","(-7650,3775)","2","mstr_standard","I76";
;
CDS_LIB"mstr_standard"
BODY_TYPE"PLUMBING"
HDL_TAP"TRUE";
"B \NAC \NWC"5;
"S \NAC"
BN"4"156;
%"TAP"
"1","(-7650,3825)","2","mstr_standard","I77";
;
CDS_LIB"mstr_standard"
BODY_TYPE"PLUMBING"
HDL_TAP"TRUE";
"B \NAC \NWC"5;
"S \NAC"
BN"5"140;
%"TAP"
"1","(-7650,3875)","2","mstr_standard","I78";
;
CDS_LIB"mstr_standard"
BODY_TYPE"PLUMBING"
HDL_TAP"TRUE";
"B \NAC \NWC"5;
"S \NAC"
BN"6"141;
%"TAP"
"1","(-7650,3925)","2","mstr_standard","I79";
;
CDS_LIB"mstr_standard"
BODY_TYPE"PLUMBING"
HDL_TAP"TRUE";
"B \NAC \NWC"5;
"S \NAC"
BN"7"157;
%"TAP"
"1","(-7650,4625)","2","mstr_standard","I80";
;
CDS_LIB"mstr_standard"
BODY_TYPE"PLUMBING"
HDL_TAP"TRUE";
"B \NAC \NWC"7;
"S \NAC"
BN"0"153;
%"TAP"
"1","(-7650,4675)","2","mstr_standard","I81";
;
CDS_LIB"mstr_standard"
BODY_TYPE"PLUMBING"
HDL_TAP"TRUE";
"B \NAC \NWC"7;
"S \NAC"
BN"1"151;
%"TAP"
"1","(-7650,4725)","2","mstr_standard","I82";
;
CDS_LIB"mstr_standard"
BODY_TYPE"PLUMBING"
HDL_TAP"TRUE";
"B \NAC \NWC"7;
"S \NAC"
BN"2"149;
%"TAP"
"1","(-7650,4775)","2","mstr_standard","I83";
;
CDS_LIB"mstr_standard"
BODY_TYPE"PLUMBING"
HDL_TAP"TRUE";
"B \NAC \NWC"7;
"S \NAC"
BN"3"25;
%"TAP"
"1","(-7650,4825)","2","mstr_standard","I84";
;
CDS_LIB"mstr_standard"
BODY_TYPE"PLUMBING"
HDL_TAP"TRUE";
"B \NAC \NWC"7;
"S \NAC"
BN"4"146;
%"TAP"
"1","(-7650,4875)","2","mstr_standard","I85";
;
CDS_LIB"mstr_standard"
BODY_TYPE"PLUMBING"
HDL_TAP"TRUE";
"B \NAC \NWC"7;
"S \NAC"
BN"5"144;
%"TAP"
"1","(-7650,4925)","2","mstr_standard","I86";
;
CDS_LIB"mstr_standard"
BODY_TYPE"PLUMBING"
HDL_TAP"TRUE";
"B \NAC \NWC"7;
"S \NAC"
BN"6"142;
%"TAP"
"1","(-7650,5025)","2","mstr_standard","I87";
;
CDS_LIB"mstr_standard"
BODY_TYPE"PLUMBING"
HDL_TAP"TRUE";
"B \NAC \NWC"6;
"S \NAC"
BN"0"154;
%"TAP"
"1","(-7650,5075)","2","mstr_standard","I88";
;
CDS_LIB"mstr_standard"
BODY_TYPE"PLUMBING"
HDL_TAP"TRUE";
"B \NAC \NWC"6;
"S \NAC"
BN"1"152;
%"TAP"
"1","(-7650,5125)","2","mstr_standard","I89";
;
CDS_LIB"mstr_standard"
BODY_TYPE"PLUMBING"
HDL_TAP"TRUE";
"B \NAC \NWC"6;
"S \NAC"
BN"2"150;
%"VCC_CORE"
"1","(-8450,3375)","0","mstr_symbols","I9";
;
HDL_POWER"P3V3_AUX"
CDS_LIB"mstr_symbols"
VOLTAGE"3.3"
ROOM"PVCCINFAON_CPU0_CTRL";
"A"166;
%"TAP"
"1","(-7650,5175)","2","mstr_standard","I90";
;
CDS_LIB"mstr_standard"
BODY_TYPE"PLUMBING"
HDL_TAP"TRUE";
"B \NAC \NWC"6;
"S \NAC"
BN"3"148;
%"TAP"
"1","(-7650,5225)","2","mstr_standard","I91";
;
CDS_LIB"mstr_standard"
BODY_TYPE"PLUMBING"
HDL_TAP"TRUE";
"B \NAC \NWC"6;
"S \NAC"
BN"4"147;
%"TAP"
"1","(-7650,5275)","2","mstr_standard","I92";
;
CDS_LIB"mstr_standard"
BODY_TYPE"PLUMBING"
HDL_TAP"TRUE";
"B \NAC \NWC"6;
"S \NAC"
BN"5"145;
%"TAP"
"1","(-7650,5325)","2","mstr_standard","I93";
;
CDS_LIB"mstr_standard"
BODY_TYPE"PLUMBING"
HDL_TAP"TRUE";
"B \NAC \NWC"6;
"S \NAC"
BN"6"143;
%"TAP"
"1","(-5950,3775)","0","mstr_standard","I94";
;
CDS_LIB"mstr_standard"
BODY_TYPE"PLUMBING"
HDL_TAP"TRUE";
"B \NAC \NWC"8;
"S \NAC"
BN"0"106;
%"TAP"
"1","(-5950,3875)","0","mstr_standard","I95";
;
CDS_LIB"mstr_standard"
BODY_TYPE"PLUMBING"
HDL_TAP"TRUE";
"B \NAC \NWC"8;
"S \NAC"
BN"2"108;
%"TAP"
"1","(-5950,3825)","0","mstr_standard","I96";
;
CDS_LIB"mstr_standard"
BODY_TYPE"PLUMBING"
HDL_TAP"TRUE";
"B \NAC \NWC"8;
"S \NAC"
BN"1"107;
%"TAP"
"1","(-5950,3925)","0","mstr_standard","I97";
;
CDS_LIB"mstr_standard"
BODY_TYPE"PLUMBING"
HDL_TAP"TRUE";
"B \NAC \NWC"8;
"S \NAC"
BN"3"109;
%"TAP"
"1","(-5950,3975)","0","mstr_standard","I98";
;
CDS_LIB"mstr_standard"
BODY_TYPE"PLUMBING"
HDL_TAP"TRUE";
"B \NAC \NWC"8;
"S \NAC"
BN"4"110;
%"TAP"
"1","(-5950,4025)","0","mstr_standard","I99";
;
CDS_LIB"mstr_standard"
BODY_TYPE"PLUMBING"
HDL_TAP"TRUE";
"B \NAC \NWC"8;
"S \NAC"
BN"5"111;
END.
